# S9S_MB_2U (Grand Teton) — schematic netlist excerpt (pin names and nets, part order shuffled) for the footprints in the layout excerpt that follows; sources: Cadence DE-HDL packaged netlist, KiCad conversion of 03242023_DA0F0TMBIJ0_F0T_Motherboard_J_brd_V01_OCP.brd

C700  Q_CAP_DIFFBUS  DIFF BUS_0.22UF 6.3V 20% X6S  pkg C0201  page 177 : \1\ = P5E_CPU1_PE4_TX_C_DN<4> ; \2\ = P5E_CPU1_PE4_TX_DN<4>
R1642  Q_RES  10K 1% CHIP  pkg 0402LF  page 260 : A = P12V_AUX ; B = VR_P5V_EN_D_R
R210  Q_RES  0 5% CHIP  pkg 0402LF  page 122 : A = H_CPU1_MEMHOT_IN_LVC1_R_N ; B = H_CPU1_MEMHOT_IN_LVC1_R1_N

(kicad_pcb
	(version 20260206)
	(generator "pcbnew")
	(generator_version "10.0")
	(general
		(thickness 1.6)
		(legacy_teardrops no)
	)
	(paper "A4")
	(title_block
		(title "03242023_DA0F0TMBIJ0_F0T_Motherboard_J_brd_V01_OCP.brd")
		(comment 1 "Grand Teton / footprints 3502-3504 of 6105")
	)
	(layers
		(0 "F.Cu" signal "TOP")
		(4 "In1.Cu" signal "GND")
		(6 "In2.Cu" signal "IN1")
		(8 "In3.Cu" signal "GND1")
		(10 "In4.Cu" signal "IN2")
		(12 "In5.Cu" signal "GND2")
		(14 "In6.Cu" signal "IN3")
		(16 "In7.Cu" signal "GND3")
		(18 "In8.Cu" signal "VCC")
		(20 "In9.Cu" signal "VCC1")
		(22 "In10.Cu" signal "GND4")
		(24 "In11.Cu" signal "IN4")
		(26 "In12.Cu" signal "GND5")
		(28 "In13.Cu" signal "IN5")
		(30 "In14.Cu" signal "GND6")
		(32 "In15.Cu" signal "IN6")
		(34 "In16.Cu" signal "GND7")
		(2 "B.Cu" signal "BOTTOM")
		(9 "F.Adhes" user "F.Adhesive")
		(11 "B.Adhes" user "B.Adhesive")
		(13 "F.Paste" user "Package Geometry/Pastemask Top")
		(15 "B.Paste" user "Package Geometry/Pastemask Bottom")
		(5 "F.SilkS" user "Ref Des/Silkscreen Top")
		(7 "B.SilkS" user "Ref Des/Silkscreen Bottom")
		(1 "F.Mask" user "Board Geometry/Soldermask Top")
		(3 "B.Mask" user "Board Geometry/Soldermask Bottom")
		(17 "Dwgs.User" user "User.Drawings")
		(19 "Cmts.User" user "User.Comments")
		(21 "Eco1.User" user "User.Eco1")
		(23 "Eco2.User" user "User.Eco2")
		(25 "Edge.Cuts" user "Board Geometry/Outline")
		(27 "Margin" user)
		(31 "F.CrtYd" user "Package Geometry/Place Bound Top")
		(29 "B.CrtYd" user "Package Geometry/Place Bound Bottom")
		(35 "F.Fab" user "Ref Des/Assembly Top")
		(33 "B.Fab" user "Ref Des/Assembly Bottom")
	)
	(footprint ""
		(layer "F.Cu")
		(at 61.553598 -408.517344 -90)
		(property "Reference" "C700"
			(at 0 0 270)
			(layer "F.SilkS")
			(hide yes)
			(effects
				(font
					(size 1.27 1.27)
				)
			)
		)
		(property "Value" ""
			(at 0 0 270)
			(layer "F.Fab")
			(effects
				(font
					(size 1.27 1.27)
				)
			)
		)
		(duplicate_pad_numbers_are_jumpers no)
		(fp_line
			(start -0.299974 0.150114)
			(end -0.299974 -0.150114)
			(stroke
				(width 0.1)
				(type default)
			)
			(layer "F.Fab")
		)
		(fp_line
			(start 0.299974 0.150114)
			(end -0.299974 0.150114)
			(stroke
				(width 0.1)
				(type default)
			)
			(layer "F.Fab")
		)
		(fp_line
			(start -0.299974 -0.150114)
			(end 0.299974 -0.150114)
			(stroke
				(width 0.1)
				(type default)
			)
			(layer "F.Fab")
		)
		(fp_line
			(start 0.299974 -0.150114)
			(end 0.299974 0.150114)
			(stroke
				(width 0.1)
				(type default)
			)
			(layer "F.Fab")
		)
		(pad "1" smd rect
			(at -0.2667 0 270)
			(size 0.3048 0.381)
			(layers "F.Cu" "F.Mask" "F.Paste")
			(net "P5E_CPU1_PE4_TX_C_DN<4>")
		)
		(pad "2" smd rect
			(at 0.2667 0 270)
			(size 0.3048 0.381)
			(layers "F.Cu" "F.Mask" "F.Paste")
			(net "P5E_CPU1_PE4_TX_DN<4>")
		)
	)
	(footprint ""
		(layer "F.Cu")
		(at 197.41388 -101.145848)
		(property "Reference" "R210"
			(at 0 0 0)
			(layer "F.SilkS")
			(hide yes)
			(effects
				(font
					(size 1.27 1.27)
				)
			)
		)
		(property "Value" ""
			(at 0 0 0)
			(layer "F.Fab")
			(effects
				(font
					(size 1.27 1.27)
				)
			)
		)
		(duplicate_pad_numbers_are_jumpers no)
		(fp_line
			(start -0.7874 -0.4064)
			(end 0.7874 -0.4064)
			(stroke
				(width 0.1524)
				(type default)
			)
			(layer "F.SilkS")
		)
		(fp_line
			(start -0.7874 0.4064)
			(end -0.7874 -0.4064)
			(stroke
				(width 0.1524)
				(type default)
			)
			(layer "F.SilkS")
		)
		(fp_line
			(start 0.7874 -0.4064)
			(end 0.7874 0.4064)
			(stroke
				(width 0.1524)
				(type default)
			)
			(layer "F.SilkS")
		)
		(fp_line
			(start 0.7874 0.4064)
			(end -0.7874 0.4064)
			(stroke
				(width 0.1524)
				(type default)
			)
			(layer "F.SilkS")
		)
		(fp_line
			(start -0.67945 -0.305054)
			(end -0.12065 -0.305054)
			(stroke
				(width 0.1)
				(type default)
			)
			(layer "F.Fab")
		)
		(fp_line
			(start -0.67945 0.3048)
			(end -0.67945 -0.305054)
			(stroke
				(width 0.1)
				(type default)
			)
			(layer "F.Fab")
		)
		(fp_line
			(start -0.12065 -0.305054)
			(end -0.12065 -0.2794)
			(stroke
				(width 0.1)
				(type default)
			)
			(layer "F.Fab")
		)
		(fp_line
			(start -0.12065 -0.2794)
			(end 0.12065 -0.2794)
			(stroke
				(width 0.1)
				(type default)
			)
			(layer "F.Fab")
		)
		(fp_line
			(start -0.12065 0.2794)
			(end -0.12065 0.3048)
			(stroke
				(width 0.1)
				(type default)
			)
			(layer "F.Fab")
		)
		(fp_line
			(start -0.12065 0.3048)
			(end -0.67945 0.3048)
			(stroke
				(width 0.1)
				(type default)
			)
			(layer "F.Fab")
		)
		(fp_line
			(start 0.120396 0.2794)
			(end -0.12065 0.2794)
			(stroke
				(width 0.1)
				(type default)
			)
			(layer "F.Fab")
		)
		(fp_line
			(start 0.120396 0.3048)
			(end 0.120396 0.2794)
			(stroke
				(width 0.1)
				(type default)
			)
			(layer "F.Fab")
		)
		(fp_line
			(start 0.12065 -0.3048)
			(end 0.67945 -0.3048)
			(stroke
				(width 0.1)
				(type default)
			)
			(layer "F.Fab")
		)
		(fp_line
			(start 0.12065 -0.2794)
			(end 0.12065 -0.3048)
			(stroke
				(width 0.1)
				(type default)
			)
			(layer "F.Fab")
		)
		(fp_line
			(start 0.67945 -0.3048)
			(end 0.67945 0.3048)
			(stroke
				(width 0.1)
				(type default)
			)
			(layer "F.Fab")
		)
		(fp_line
			(start 0.67945 0.3048)
			(end 0.120396 0.3048)
			(stroke
				(width 0.1)
				(type default)
			)
			(layer "F.Fab")
		)
		(pad "1" smd circle
			(at -0.40005 0)
			(size 0 0)
			(layers "F.Cu" "F.Mask" "F.Paste")
			(net "H_CPU1_MEMHOT_IN_LVC1_R_N")
		)
		(pad "2" smd circle
			(at 0.40005 0)
			(size 0 0)
			(layers "F.Cu" "F.Mask" "F.Paste")
			(net "H_CPU1_MEMHOT_IN_LVC1_R1_N")
		)
	)
	(footprint ""
		(layer "F.Cu")
		(at 165.31463 -133.77672 -90)
		(property "Reference" "R1642"
			(at 0 0 270)
			(layer "F.SilkS")
			(hide yes)
			(effects
				(font
					(size 1.27 1.27)
				)
			)
		)
		(property "Value" ""
			(at 0 0 270)
			(layer "F.Fab")
			(effects
				(font
					(size 1.27 1.27)
				)
			)
		)
		(duplicate_pad_numbers_are_jumpers no)
		(fp_line
			(start -0.7874 0.4064)
			(end -0.7874 -0.4064)
			(stroke
				(width 0.1524)
				(type default)
			)
			(layer "F.SilkS")
		)
		(fp_line
			(start 0.7874 0.4064)
			(end -0.7874 0.4064)
			(stroke
				(width 0.1524)
				(type default)
			)
			(layer "F.SilkS")
		)
		(fp_line
			(start -0.7874 -0.4064)
			(end 0.7874 -0.4064)
			(stroke
				(width 0.1524)
				(type default)
			)
			(layer "F.SilkS")
		)
		(fp_line
			(start 0.7874 -0.4064)
			(end 0.7874 0.4064)
			(stroke
				(width 0.1524)
				(type default)
			)
			(layer "F.SilkS")
		)
		(fp_line
			(start -0.67945 0.3048)
			(end -0.67945 -0.305054)
			(stroke
				(width 0.1)
				(type default)
			)
			(layer "F.Fab")
		)
		(fp_line
			(start -0.12065 0.3048)
			(end -0.67945 0.3048)
			(stroke
				(width 0.1)
				(type default)
			)
			(layer "F.Fab")
		)
		(fp_line
			(start 0.120396 0.3048)
			(end 0.120396 0.2794)
			(stroke
				(width 0.1)
				(type default)
			)
			(layer "F.Fab")
		)
		(fp_line
			(start 0.67945 0.3048)
			(end 0.120396 0.3048)
			(stroke
				(width 0.1)
				(type default)
			)
			(layer "F.Fab")
		)
		(fp_line
			(start -0.12065 0.2794)
			(end -0.12065 0.3048)
			(stroke
				(width 0.1)
				(type default)
			)
			(layer "F.Fab")
		)
		(fp_line
			(start 0.120396 0.2794)
			(end -0.12065 0.2794)
			(stroke
				(width 0.1)
				(type default)
			)
			(layer "F.Fab")
		)
		(fp_line
			(start -0.12065 -0.2794)
			(end 0.12065 -0.2794)
			(stroke
				(width 0.1)
				(type default)
			)
			(layer "F.Fab")
		)
		(fp_line
			(start 0.12065 -0.2794)
			(end 0.12065 -0.3048)
			(stroke
				(width 0.1)
				(type default)
			)
			(layer "F.Fab")
		)
		(fp_line
			(start 0.12065 -0.3048)
			(end 0.67945 -0.3048)
			(stroke
				(width 0.1)
				(type default)
			)
			(layer "F.Fab")
		)
		(fp_line
			(start 0.67945 -0.3048)
			(end 0.67945 0.3048)
			(stroke
				(width 0.1)
				(type default)
			)
			(layer "F.Fab")
		)
		(fp_line
			(start -0.67945 -0.305054)
			(end -0.12065 -0.305054)
			(stroke
				(width 0.1)
				(type default)
			)
			(layer "F.Fab")
		)
		(fp_line
			(start -0.12065 -0.305054)
			(end -0.12065 -0.2794)
			(stroke
				(width 0.1)
				(type default)
			)
			(layer "F.Fab")
		)
		(pad "1" smd circle
			(at -0.40005 0 270)
			(size 0 0)
			(layers "F.Cu" "F.Mask" "F.Paste")
			(net "P12V_AUX")
		)
		(pad "2" smd circle
			(at 0.40005 0 270)
			(size 0 0)
			(layers "F.Cu" "F.Mask" "F.Paste")
			(net "VR_P5V_EN_D_R")
		)
	)
)
